# T6G (Grand Teton) — schematic netlist excerpt (pin names and nets, part order shuffled) for the footprints in the layout excerpt that follows; sources: Cadence DE-HDL packaged netlist, KiCad conversion of 04192023_DAF0TMB3IC0_F0TG_MB_C_brd_V02_OCP.brd

C6523  Q_CAP_DIFFBUS  DIFF BUS_0.22UF 6.3V 20% X6S  pkg C0201  page 275 : \1\ = P5E_CPU0_P0_TX_BUF_C_DP<11> ; \2\ = P5E_CPU0_P0_TX_BUF_DP<11>
C8010  Q_CAP  0.1UF 25V 10% X7R  pkg 0402  page 147 : A = P3V3_E1S_0_R ; B = GND
R895  Q_RES  0 5% CHIP  pkg 0201LF  page 353 : A = RST_RT_CPU1_P3_PERST_N ; B = RST_RT_CPU1_P3_PERST_R_N

(kicad_pcb
	(version 20260206)
	(generator "pcbnew")
	(generator_version "10.0")
	(general
		(thickness 1.6)
		(legacy_teardrops no)
	)
	(paper "A4")
	(title_block
		(title "04192023_DAF0TMB3IC0_F0TG_MB_C_brd_V02_OCP.brd")
		(comment 1 "Grand Teton / footprints 1188-1190 of 8354")
	)
	(layers
		(0 "F.Cu" signal "TOP")
		(4 "In1.Cu" signal "GND")
		(6 "In2.Cu" signal "IN1")
		(8 "In3.Cu" signal "GND1")
		(10 "In4.Cu" signal "IN2")
		(12 "In5.Cu" signal "GND2")
		(14 "In6.Cu" signal "IN3")
		(16 "In7.Cu" signal "GND3")
		(18 "In8.Cu" signal "VCC")
		(20 "In9.Cu" signal "VCC1")
		(22 "In10.Cu" signal "GND4")
		(24 "In11.Cu" signal "IN4")
		(26 "In12.Cu" signal "GND5")
		(28 "In13.Cu" signal "IN5")
		(30 "In14.Cu" signal "GND6")
		(32 "In15.Cu" signal "IN6")
		(34 "In16.Cu" signal "GND7")
		(2 "B.Cu" signal "BOTTOM")
		(9 "F.Adhes" user "F.Adhesive")
		(11 "B.Adhes" user "B.Adhesive")
		(13 "F.Paste" user "Package Geometry/Pastemask Top")
		(15 "B.Paste" user "Package Geometry/Pastemask Bottom")
		(5 "F.SilkS" user "Ref Des/Silkscreen Top")
		(7 "B.SilkS" user "Ref Des/Silkscreen Bottom")
		(1 "F.Mask" user "Board Geometry/Soldermask Top")
		(3 "B.Mask" user "Board Geometry/Soldermask Bottom")
		(17 "Dwgs.User" user "User.Drawings")
		(19 "Cmts.User" user "User.Comments")
		(21 "Eco1.User" user "User.Eco1")
		(23 "Eco2.User" user "User.Eco2")
		(25 "Edge.Cuts" user "Board Geometry/Outline")
		(27 "Margin" user)
		(31 "F.CrtYd" user "Package Geometry/Place Bound Top")
		(29 "B.CrtYd" user "Package Geometry/Place Bound Bottom")
		(35 "F.Fab" user "Ref Des/Assembly Top")
		(33 "B.Fab" user "Ref Des/Assembly Bottom")
	)
	(footprint ""
		(layer "F.Cu")
		(at 223.393 -76.581 180)
		(property "Reference" "C8010"
			(at 0 0 180)
			(layer "F.SilkS")
			(hide yes)
			(effects
				(font
					(size 1.27 1.27)
				)
			)
		)
		(property "Value" ""
			(at 0 0 180)
			(layer "F.Fab")
			(effects
				(font
					(size 1.27 1.27)
				)
			)
		)
		(duplicate_pad_numbers_are_jumpers no)
		(fp_line
			(start 0.7874 0.4064)
			(end -0.7874 0.4064)
			(stroke
				(width 0.1524)
				(type default)
			)
			(layer "F.SilkS")
		)
		(fp_line
			(start 0.7874 -0.4064)
			(end 0.7874 0.4064)
			(stroke
				(width 0.1524)
				(type default)
			)
			(layer "F.SilkS")
		)
		(fp_line
			(start -0.7874 0.4064)
			(end -0.7874 -0.4064)
			(stroke
				(width 0.1524)
				(type default)
			)
			(layer "F.SilkS")
		)
		(fp_line
			(start -0.7874 -0.4064)
			(end 0.7874 -0.4064)
			(stroke
				(width 0.1524)
				(type default)
			)
			(layer "F.SilkS")
		)
		(fp_line
			(start 0.67945 0.3048)
			(end 0.120396 0.3048)
			(stroke
				(width 0.1)
				(type default)
			)
			(layer "F.Fab")
		)
		(fp_line
			(start 0.67945 -0.3048)
			(end 0.67945 0.3048)
			(stroke
				(width 0.1)
				(type default)
			)
			(layer "F.Fab")
		)
		(fp_line
			(start 0.12065 -0.2794)
			(end 0.12065 -0.3048)
			(stroke
				(width 0.1)
				(type default)
			)
			(layer "F.Fab")
		)
		(fp_line
			(start 0.12065 -0.3048)
			(end 0.67945 -0.3048)
			(stroke
				(width 0.1)
				(type default)
			)
			(layer "F.Fab")
		)
		(fp_line
			(start 0.120396 0.3048)
			(end 0.120396 0.2794)
			(stroke
				(width 0.1)
				(type default)
			)
			(layer "F.Fab")
		)
		(fp_line
			(start 0.120396 0.2794)
			(end -0.12065 0.2794)
			(stroke
				(width 0.1)
				(type default)
			)
			(layer "F.Fab")
		)
		(fp_line
			(start -0.12065 0.3048)
			(end -0.67945 0.3048)
			(stroke
				(width 0.1)
				(type default)
			)
			(layer "F.Fab")
		)
		(fp_line
			(start -0.12065 0.2794)
			(end -0.12065 0.3048)
			(stroke
				(width 0.1)
				(type default)
			)
			(layer "F.Fab")
		)
		(fp_line
			(start -0.12065 -0.2794)
			(end 0.12065 -0.2794)
			(stroke
				(width 0.1)
				(type default)
			)
			(layer "F.Fab")
		)
		(fp_line
			(start -0.12065 -0.305054)
			(end -0.12065 -0.2794)
			(stroke
				(width 0.1)
				(type default)
			)
			(layer "F.Fab")
		)
		(fp_line
			(start -0.67945 0.3048)
			(end -0.67945 -0.305054)
			(stroke
				(width 0.1)
				(type default)
			)
			(layer "F.Fab")
		)
		(fp_line
			(start -0.67945 -0.305054)
			(end -0.12065 -0.305054)
			(stroke
				(width 0.1)
				(type default)
			)
			(layer "F.Fab")
		)
		(pad "1" smd circle
			(at -0.40005 0 180)
			(size 0 0)
			(layers "F.Cu" "F.Mask" "F.Paste")
			(net "P3V3_E1S_0_R")
		)
		(pad "2" smd circle
			(at 0.40005 0 180)
			(size 0 0)
			(layers "F.Cu" "F.Mask" "F.Paste")
			(net "GND")
		)
	)
	(footprint ""
		(layer "F.Cu")
		(at 338.378546 -416.899344 -90)
		(property "Reference" "C6523"
			(at 0 0 270)
			(layer "F.SilkS")
			(hide yes)
			(effects
				(font
					(size 1.27 1.27)
				)
			)
		)
		(property "Value" ""
			(at 0 0 270)
			(layer "F.Fab")
			(effects
				(font
					(size 1.27 1.27)
				)
			)
		)
		(duplicate_pad_numbers_are_jumpers no)
		(fp_line
			(start -0.299974 0.150114)
			(end -0.299974 -0.150114)
			(stroke
				(width 0.1)
				(type default)
			)
			(layer "F.Fab")
		)
		(fp_line
			(start 0.299974 0.150114)
			(end -0.299974 0.150114)
			(stroke
				(width 0.1)
				(type default)
			)
			(layer "F.Fab")
		)
		(fp_line
			(start -0.299974 -0.150114)
			(end 0.299974 -0.150114)
			(stroke
				(width 0.1)
				(type default)
			)
			(layer "F.Fab")
		)
		(fp_line
			(start 0.299974 -0.150114)
			(end 0.299974 0.150114)
			(stroke
				(width 0.1)
				(type default)
			)
			(layer "F.Fab")
		)
		(pad "1" smd rect
			(at -0.2667 0 270)
			(size 0.3048 0.381)
			(layers "F.Cu" "F.Mask" "F.Paste")
			(net "P5E_CPU0_P0_TX_BUF_C_DP<11>")
		)
		(pad "2" smd rect
			(at 0.2667 0 270)
			(size 0.3048 0.381)
			(layers "F.Cu" "F.Mask" "F.Paste")
			(net "P5E_CPU0_P0_TX_BUF_DP<11>")
		)
	)
	(footprint ""
		(layer "F.Cu")
		(at 135.268462 -395.6304 -90)
		(property "Reference" "R895"
			(at 0 0 270)
			(layer "F.SilkS")
			(hide yes)
			(effects
				(font
					(size 1.27 1.27)
				)
			)
		)
		(property "Value" ""
			(at 0 0 270)
			(layer "F.Fab")
			(effects
				(font
					(size 1.27 1.27)
				)
			)
		)
		(duplicate_pad_numbers_are_jumpers no)
		(fp_line
			(start -0.32512 0.175006)
			(end -0.32512 -0.175006)
			(stroke
				(width 0.1)
				(type default)
			)
			(layer "F.Fab")
		)
		(fp_line
			(start 0.32512 0.175006)
			(end -0.32512 0.175006)
			(stroke
				(width 0.1)
				(type default)
			)
			(layer "F.Fab")
		)
		(fp_line
			(start -0.32512 -0.175006)
			(end 0.32512 -0.175006)
			(stroke
				(width 0.1)
				(type default)
			)
			(layer "F.Fab")
		)
		(fp_line
			(start 0.32512 -0.175006)
			(end 0.32512 0.175006)
			(stroke
				(width 0.1)
				(type default)
			)
			(layer "F.Fab")
		)
		(pad "1" smd rect
			(at -0.2667 0 270)
			(size 0.3048 0.381)
			(layers "F.Cu" "F.Mask" "F.Paste")
			(net "RST_RT_CPU1_P3_PERST_N")
		)
		(pad "2" smd rect
			(at 0.2667 0 90)
			(size 0.3048 0.381)
			(layers "F.Cu" "F.Mask" "F.Paste")
			(net "RST_RT_CPU1_P3_PERST_R_N")
		)
	)
)
